FILE_TYPE = CONNECTIVITY;
{Allegro Design Entry HDL 16.6-p007 (v16-6-112F) 10/10/2012}
"PAGE_NUMBER" = 85;
0"NC";
1"M_L_DQS_DP<17:0>";
2"M_L_DQS_DN<17:0>";
3"M_L_DQ<63:0>";
4"M_L_MA<17:0>";
5"M_L_CS_N<7:0>";
6"M_L_CKE<3:0>";
7"M_L_ODT<3:0>";
8"M_L_ECC<7:0>";
9"M_L_CLK_DN<3:0>";
10"M_L_CLK_DP<3:0>";
11"M_L_BA<1:0>";
12"M_L_BG<1:0>";
13"PVDDQ_KLM\g";
14"PVTT_KLM\g";
15"GND\g";
16"GND\g";
17"GND\g";
18"PVPP_KLM\g";
19"PVPP_KLM\g";
20"P12V_NVDIMM_KLM\g";
21"GND\g";
22"M_L_DQS_DN<0>";
23"TP_CH_L_DIMM_L0_RFU_2";
24"M_L_DQS_DN<10>";
25"M_L_DQ<58>";
26"M_L_DQ<59>";
27"M_L_DQ<36>";
28"M_L_ACT_N";
29"M_L_VREF";
30"TP_CH_L_DIMM_L0_RFU_0";
31"TP_CH_L_DIMM_L0_RFU_1";
32"SMB_DDR_KLM_VPP_SDA";
33"SMB_DDR_KLM_VPP_SCL";
34"FM_ADR_COMPLETE_KLM_N";
35"FM_DIMM_EVENT_COD_N";
36"M_L_PAR";
37"M_KLM_RST_N";
38"M_L_C<2>";
39"M_L_BG<0>";
40"M_L_BG<1>";
41"M_L_BA<0>";
42"M_L_BA<1>";
43"M_L_CLK_DP<1>";
44"M_L_CLK_DN<1>";
45"M_L_CS_N<3>";
46"M_L_CLK_DP<0>";
47"M_L_CS_N<2>";
48"M_L_CS_N<1>";
49"M_L_MA<0>";
50"M_L_ECC<7>";
51"M_L_ECC<4>";
52"M_L_ECC<5>";
53"M_L_ECC<2>";
54"M_L_ECC<3>";
55"M_L_ECC<0>";
56"M_L_ECC<1>";
57"M_L_CLK_DN<0>";
58"M_L_CKE<1>";
59"M_L_ECC<6>";
60"M_L_ODT<0>";
61"M_L_ODT<1>";
62"M_L_CKE<0>";
63"M_L_CS_N<0>";
64"M_L_ALERT_N";
65"M_L_DQ<1>";
66"M_L_DQ<0>";
67"M_L_DQ<3>";
68"M_L_DQ<2>";
69"M_L_DQ<5>";
70"M_L_DQ<4>";
71"M_L_DQ<10>";
72"M_L_DQ<11>";
73"M_L_DQ<8>";
74"M_L_DQ<9>";
75"M_L_DQ<6>";
76"M_L_DQ<7>";
77"M_L_DQ<17>";
78"M_L_DQ<15>";
79"M_L_DQ<12>";
80"M_L_DQ<13>";
81"M_L_DQ<14>";
82"M_L_DQ<18>";
83"M_L_DQ<20>";
84"M_L_DQ<21>";
85"M_L_DQ<19>";
86"M_L_DQ<16>";
87"M_L_DQ<23>";
88"M_L_DQ<22>";
89"M_L_DQ<25>";
90"M_L_DQ<24>";
91"M_L_DQ<27>";
92"M_L_DQ<28>";
93"M_L_DQ<29>";
94"M_L_DQ<30>";
95"M_L_DQ<31>";
96"M_L_DQ<26>";
97"M_L_DQ<32>";
98"M_L_DQ<35>";
99"M_L_DQ<33>";
100"M_L_DQ<34>";
101"M_L_DQ<37>";
102"M_L_DQ<38>";
103"M_L_DQ<40>";
104"M_L_DQ<41>";
105"M_L_DQ<39>";
106"M_L_DQ<42>";
107"M_L_DQ<45>";
108"M_L_DQ<44>";
109"M_L_DQ<47>";
110"M_L_DQ<43>";
111"M_L_MA<1>";
112"M_L_MA<12>";
113"M_L_MA<13>";
114"M_L_MA<17>";
115"M_L_MA<3>";
116"M_L_MA<4>";
117"M_L_MA<5>";
118"M_L_MA<6>";
119"M_L_MA<7>";
120"M_L_MA<8>";
121"M_L_MA<9>";
122"M_L_MA<2>";
123"M_L_MA<10>";
124"M_L_MA<11>";
125"M_L_MA<14>";
126"M_L_MA<15>";
127"M_L_MA<16>";
128"M_L_DQ<46>";
129"M_L_DQ<49>";
130"M_L_DQ<48>";
131"M_L_DQ<51>";
132"M_L_DQ<50>";
133"M_L_DQ<53>";
134"M_L_DQ<54>";
135"M_L_DQ<57>";
136"M_L_DQ<56>";
137"M_L_DQ<55>";
138"M_L_DQ<52>";
139"M_L_DQ<60>";
140"M_L_DQ<61>";
141"M_L_DQ<63>";
142"M_L_DQ<62>";
143"M_L_DQS_DP<0>";
144"M_L_DQS_DN<1>";
145"M_L_DQS_DP<1>";
146"M_L_DQS_DN<2>";
147"M_L_DQS_DP<2>";
148"M_L_DQS_DN<3>";
149"M_L_DQS_DP<3>";
150"M_L_DQS_DN<4>";
151"M_L_DQS_DP<4>";
152"M_L_DQS_DN<5>";
153"M_L_DQS_DP<5>";
154"M_L_DQS_DN<6>";
155"M_L_DQS_DP<6>";
156"M_L_DQS_DP<10>";
157"M_L_DQS_DN<11>";
158"M_L_DQS_DP<11>";
159"M_L_DQS_DN<12>";
160"M_L_DQS_DP<12>";
161"M_L_DQS_DN<13>";
162"M_L_DQS_DP<13>";
163"M_L_DQS_DN<14>";
164"M_L_DQS_DP<14>";
165"M_L_DQS_DN<15>";
166"M_L_DQS_DP<15>";
167"M_L_DQS_DN<16>";
168"M_L_DQS_DP<16>";
169"M_L_DQS_DN<17>";
170"M_L_DQS_DN<7>";
171"M_L_DQS_DP<7>";
172"M_L_DQS_DN<8>";
173"M_L_DQS_DP<8>";
174"M_L_DQS_DN<9>";
175"M_L_DQS_DP<9>";
176"M_L_DQS_DP<17>";
%"TAP"
"6","(700,4850)","2","mstr_standard","I10";
;
CDS_LIB"mstr_standard"
BODY_TYPE"PLUMBING"
HDL_TAP"TRUE";
"B \NAC \NWC"1;
"S \NAC"
BN"14"164;
%"TAP"
"6","(-1750,2200)","2","mstr_standard","I100";
;
CDS_LIB"mstr_standard"
BODY_TYPE"PLUMBING"
HDL_TAP"TRUE";
"B \NAC \NWC"3;
"S \NAC"
BN"8"73;
%"TAP"
"6","(-1750,2250)","2","mstr_standard","I101";
;
CDS_LIB"mstr_standard"
BODY_TYPE"PLUMBING"
HDL_TAP"TRUE";
"B \NAC \NWC"3;
"S \NAC"
BN"11"72;
%"TAP"
"6","(-1750,1950)","2","mstr_standard","I102";
;
CDS_LIB"mstr_standard"
BODY_TYPE"PLUMBING"
HDL_TAP"TRUE";
"B \NAC \NWC"3;
"S \NAC"
BN"5"69;
%"TAP"
"6","(-1750,1900)","2","mstr_standard","I103";
;
CDS_LIB"mstr_standard"
BODY_TYPE"PLUMBING"
HDL_TAP"TRUE";
"B \NAC \NWC"3;
"S \NAC"
BN"2"68;
%"TAP"
"6","(-1750,2000)","2","mstr_standard","I104";
;
CDS_LIB"mstr_standard"
BODY_TYPE"PLUMBING"
HDL_TAP"TRUE";
"B \NAC \NWC"3;
"S \NAC"
BN"4"70;
%"TAP"
"6","(-1750,2050)","2","mstr_standard","I105";
;
CDS_LIB"mstr_standard"
BODY_TYPE"PLUMBING"
HDL_TAP"TRUE";
"B \NAC \NWC"3;
"S \NAC"
BN"7"76;
%"TAP"
"6","(-1750,2150)","2","mstr_standard","I106";
;
CDS_LIB"mstr_standard"
BODY_TYPE"PLUMBING"
HDL_TAP"TRUE";
"B \NAC \NWC"3;
"S \NAC"
BN"9"74;
%"TAP"
"6","(-1750,2100)","2","mstr_standard","I107";
;
CDS_LIB"mstr_standard"
BODY_TYPE"PLUMBING"
HDL_TAP"TRUE";
"B \NAC \NWC"3;
"S \NAC"
BN"6"75;
%"TAP"
"6","(-1750,1750)","2","mstr_standard","I108";
;
CDS_LIB"mstr_standard"
BODY_TYPE"PLUMBING"
HDL_TAP"TRUE";
"B \NAC \NWC"3;
"S \NAC"
BN"1"65;
%"TAP"
"6","(-1750,1850)","2","mstr_standard","I109";
;
CDS_LIB"mstr_standard"
BODY_TYPE"PLUMBING"
HDL_TAP"TRUE";
"B \NAC \NWC"3;
"S \NAC"
BN"3"67;
%"TAP"
"6","(700,4950)","2","mstr_standard","I11";
;
CDS_LIB"mstr_standard"
BODY_TYPE"PLUMBING"
HDL_TAP"TRUE";
"B \NAC \NWC"1;
"S \NAC"
BN"15"166;
%"TAP"
"6","(-1750,1800)","2","mstr_standard","I110";
;
CDS_LIB"mstr_standard"
BODY_TYPE"PLUMBING"
HDL_TAP"TRUE";
"B \NAC \NWC"3;
"S \NAC"
BN"0"66;
%"SCONN288_H44441004"
"1","(-2500,3250)","0","mstr_sconn","I111";
;
CDS_SEC"1"
LOCATION"J1A2"
PART_NUMBER"H44441-004"
MATERIAL"SCONN"
PACK_TYPE"PIP"
BOM_COST"MEM"
CDS_LIB"mstr_sconn"
SEC_TYPE"PIP"
SEC"1"
CDS_LOCATION"J1A2"
ROOM"DDR4_CH_L";
"DQ<63>"
$PN"280"142;
"DQ<62>"
$PN"135"141;
"DQ<61>"
$PN"273"139;
"DQ<5>"
$PN"148"70;
"DQ<4>"
$PN"3"69;
"DQ<3>"
$PN"157"68;
"DQ<2>"
$PN"12"67;
"DQ<47>"
$PN"258"128;
"DQ<48>"
$PN"119"129;
"DQ<49>"
$PN"264"130;
"DQ<50>"
$PN"126"131;
"DQ<51>"
$PN"271"132;
"DQ<52>"
$PN"117"133;
"DQ<53>"
$PN"262"138;
"DQ<54>"
$PN"124"137;
"DQ<58>"
$PN"137"26;
"DQ<57>"
$PN"275"136;
"SAVE_N_NC"
$PN"230"34;
"RFU<1>"
$PN"227"31;
"RFU<0>"
$PN"205"30;
"DQ<17>"
$PN"172"86;
"DQ<15>"
$PN"166"81;
"DQ<26>"
$PN"45"91;
"DQ<27>"
$PN"190"96;
"S0_N"
$PN"84"63;
"CKE<0>"
$PN"60"62;
"ODT<1>"
$PN"91"61;
"ODT<0>"
$PN"87"60;
"CB<7>"
$PN"199"59;
"A16_RAS_N"
$PN"82"127;
"A15_CAS_N"
$PN"86"126;
"A14_WE_N"
$PN"228"125;
"A11"
$PN"210"124;
"A10"
$PN"225"123;
"DQ<38>"
$PN"102"105;
"DQ<36>"
$PN"95"101;
"DQ<35>"
$PN"249"100;
"A2"
$PN"216"122;
"ALERT_N"
$PN"208"64;
"ACT_N"
$PN"62"28;
"DQ<0>"
$PN"5"65;
"DQ<1>"
$PN"150"66;
"SA<1>"
$PN"140"19;
"SA<2>"
$PN"238"16;
"VDDSPD"
$PN"284"19;
"SA<0>"
$PN"139"16;
"BA<0>"
$PN"81"41;
"BG<1>"
$PN"207"40;
"BG<0>"
$PN"63"39;
"CK1P"
$PN"218"43;
"VREFCA"
$PN"146"29;
"SDA"
$PN"285"32;
"SCL"
$PN"141"33;
"RFU<2>"
$PN"144"23;
"RESET_N"
$PN"58"37;
"PAR"
$PN"222"36;
"EVENT_N"
$PN"78"35;
"DQ<6>"
$PN"10"76;
"DQ<7>"
$PN"155"75;
"DQ<8>"
$PN"16"74;
"DQ<9>"
$PN"161"73;
"DQ<10>"
$PN"23"72;
"DQ<11>"
$PN"168"71;
"DQ<12>"
$PN"14"80;
"DQ<13>"
$PN"159"79;
"DQ<14>"
$PN"21"78;
"DQ<16>"
$PN"27"77;
"DQ<18>"
$PN"34"85;
"DQ<19>"
$PN"179"82;
"DQ<20>"
$PN"25"84;
"DQ<21>"
$PN"170"83;
"DQ<22>"
$PN"32"87;
"DQ<23>"
$PN"177"88;
"DQ<24>"
$PN"38"89;
"DQ<25>"
$PN"183"90;
"DQ<30>"
$PN"43"95;
"DQ<31>"
$PN"188"94;
"DQ<32>"
$PN"97"99;
"DQ<33>"
$PN"242"97;
"DQ<34>"
$PN"104"98;
"DQ<37>"
$PN"240"27;
"DQ<39>"
$PN"247"102;
"DQ<40>"
$PN"108"104;
"DQ<41>"
$PN"253"103;
"DQ<42>"
$PN"115"110;
"DQ<43>"
$PN"260"106;
"DQ<44>"
$PN"106"107;
"DQ<45>"
$PN"251"108;
"DQ<46>"
$PN"113"109;
"DQ<55>"
$PN"269"134;
"DQ<56>"
$PN"130"135;
"DQ<59>"
$PN"282"25;
"DQ<60>"
$PN"128"140;
"CKE<1>"
$PN"203"58;
"CK0N"
$PN"75"57;
"CB<0>"
$PN"49"56;
"CB<1>"
$PN"194"55;
"CB<2>"
$PN"56"54;
"CB<3>"
$PN"201"53;
"CB<4>"
$PN"47"52;
"CB<5>"
$PN"192"51;
"CB<6>"
$PN"54"50;
"A9"
$PN"66"121;
"A8"
$PN"68"120;
"A7"
$PN"211"119;
"A6"
$PN"69"118;
"A5"
$PN"213"117;
"A4"
$PN"214"116;
"A3"
$PN"71"115;
"A17"
$PN"234"114;
"A13"
$PN"232"113;
"A12"
$PN"65"112;
"A1"
$PN"72"111;
"A0"
$PN"79"49;
"C<2>"
$PN"235"38;
"DQ<28>"
$PN"36"93;
"DQ<29>"
$PN"181"92;
"S1_N"
$PN"89"48;
"S2_N_C<0>"
$PN"93"47;
"S3_N_C<1>"
$PN"237"45;
"CK0P"
$PN"74"46;
"CK1N"
$PN"219"44;
"BA<1>"
$PN"224"42;
%"TAP"
"6","(-3250,4850)","0","mstr_standard","I112";
;
CDS_LIB"mstr_standard"
BODY_TYPE"PLUMBING"
HDL_TAP"TRUE";
"B \NAC \NWC"4;
"S \NAC"
BN"16"127;
%"TAP"
"6","(-3250,4900)","0","mstr_standard","I113";
;
CDS_LIB"mstr_standard"
BODY_TYPE"PLUMBING"
HDL_TAP"TRUE";
"B \NAC \NWC"4;
"S \NAC"
BN"17"114;
%"TAP"
"6","(-3250,4800)","0","mstr_standard","I114";
;
CDS_LIB"mstr_standard"
BODY_TYPE"PLUMBING"
HDL_TAP"TRUE";
"B \NAC \NWC"4;
"S \NAC"
BN"15"126;
%"TAP"
"6","(-3250,4750)","0","mstr_standard","I115";
;
CDS_LIB"mstr_standard"
BODY_TYPE"PLUMBING"
HDL_TAP"TRUE";
"B \NAC \NWC"4;
"S \NAC"
BN"14"125;
%"TAP"
"6","(-3250,4700)","0","mstr_standard","I116";
;
CDS_LIB"mstr_standard"
BODY_TYPE"PLUMBING"
HDL_TAP"TRUE";
"B \NAC \NWC"4;
"S \NAC"
BN"13"113;
%"TAP"
"6","(-3250,4650)","0","mstr_standard","I117";
;
CDS_LIB"mstr_standard"
BODY_TYPE"PLUMBING"
HDL_TAP"TRUE";
"B \NAC \NWC"4;
"S \NAC"
BN"12"112;
%"TAP"
"6","(-3250,4600)","0","mstr_standard","I118";
;
CDS_LIB"mstr_standard"
BODY_TYPE"PLUMBING"
HDL_TAP"TRUE";
"B \NAC \NWC"4;
"S \NAC"
BN"11"124;
%"TAP"
"6","(-3250,4550)","0","mstr_standard","I119";
;
CDS_LIB"mstr_standard"
BODY_TYPE"PLUMBING"
HDL_TAP"TRUE";
"B \NAC \NWC"4;
"S \NAC"
BN"10"123;
%"TAP"
"6","(700,5050)","2","mstr_standard","I12";
;
CDS_LIB"mstr_standard"
BODY_TYPE"PLUMBING"
HDL_TAP"TRUE";
"B \NAC \NWC"1;
"S \NAC"
BN"16"168;
%"TAP"
"6","(-3250,4500)","0","mstr_standard","I120";
;
CDS_LIB"mstr_standard"
BODY_TYPE"PLUMBING"
HDL_TAP"TRUE";
"B \NAC \NWC"4;
"S \NAC"
BN"9"121;
%"TAP"
"6","(-3250,4450)","0","mstr_standard","I121";
;
CDS_LIB"mstr_standard"
BODY_TYPE"PLUMBING"
HDL_TAP"TRUE";
"B \NAC \NWC"4;
"S \NAC"
BN"8"120;
%"TAP"
"6","(-3250,4400)","0","mstr_standard","I122";
;
CDS_LIB"mstr_standard"
BODY_TYPE"PLUMBING"
HDL_TAP"TRUE";
"B \NAC \NWC"4;
"S \NAC"
BN"7"119;
%"TAP"
"6","(-3250,4350)","0","mstr_standard","I123";
;
CDS_LIB"mstr_standard"
BODY_TYPE"PLUMBING"
HDL_TAP"TRUE";
"B \NAC \NWC"4;
"S \NAC"
BN"6"118;
%"TAP"
"6","(-3250,4300)","0","mstr_standard","I124";
;
CDS_LIB"mstr_standard"
BODY_TYPE"PLUMBING"
HDL_TAP"TRUE";
"B \NAC \NWC"4;
"S \NAC"
BN"5"117;
%"TAP"
"6","(-3250,4250)","0","mstr_standard","I125";
;
CDS_LIB"mstr_standard"
BODY_TYPE"PLUMBING"
HDL_TAP"TRUE";
"B \NAC \NWC"4;
"S \NAC"
BN"4"116;
%"TAP"
"6","(-3250,4150)","0","mstr_standard","I126";
;
CDS_LIB"mstr_standard"
BODY_TYPE"PLUMBING"
HDL_TAP"TRUE";
"B \NAC \NWC"4;
"S \NAC"
BN"2"122;
%"TAP"
"6","(-3250,4200)","0","mstr_standard","I127";
;
CDS_LIB"mstr_standard"
BODY_TYPE"PLUMBING"
HDL_TAP"TRUE";
"B \NAC \NWC"4;
"S \NAC"
BN"3"115;
%"TAP"
"6","(-3250,4100)","0","mstr_standard","I128";
;
CDS_LIB"mstr_standard"
BODY_TYPE"PLUMBING"
HDL_TAP"TRUE";
"B \NAC \NWC"4;
"S \NAC"
BN"1"111;
%"TAP"
"6","(-3250,4050)","0","mstr_standard","I129";
;
CDS_LIB"mstr_standard"
BODY_TYPE"PLUMBING"
HDL_TAP"TRUE";
"B \NAC \NWC"4;
"S \NAC"
BN"0"49;
%"TAP"
"6","(700,4550)","2","mstr_standard","I13";
;
CDS_LIB"mstr_standard"
BODY_TYPE"PLUMBING"
HDL_TAP"TRUE";
"B \NAC \NWC"1;
"S \NAC"
BN"11"158;
%"TAP"
"6","(-3250,3950)","0","mstr_standard","I130";
;
CDS_LIB"mstr_standard"
BODY_TYPE"PLUMBING"
HDL_TAP"TRUE";
"B \NAC \NWC"11;
"S \NAC"
BN"1"42;
%"TAP"
"6","(-3250,3900)","0","mstr_standard","I133";
;
CDS_LIB"mstr_standard"
BODY_TYPE"PLUMBING"
HDL_TAP"TRUE";
"B \NAC \NWC"11;
"S \NAC"
BN"0"41;
%"TAP"
"6","(-3250,3850)","0","mstr_standard","I134";
;
CDS_LIB"mstr_standard"
BODY_TYPE"PLUMBING"
HDL_TAP"TRUE";
"B \NAC \NWC"12;
"S \NAC"
BN"1"40;
%"TAP"
"6","(-3250,3800)","0","mstr_standard","I135";
;
CDS_LIB"mstr_standard"
BODY_TYPE"PLUMBING"
HDL_TAP"TRUE";
"B \NAC \NWC"12;
"S \NAC"
BN"0"39;
%"TAP"
"6","(-3250,2850)","0","mstr_standard","I138";
;
CDS_LIB"mstr_standard"
BODY_TYPE"PLUMBING"
HDL_TAP"TRUE";
"B \NAC \NWC"8;
"S \NAC"
BN"6"59;
%"TAP"
"6","(-3250,2800)","0","mstr_standard","I139";
;
CDS_LIB"mstr_standard"
BODY_TYPE"PLUMBING"
HDL_TAP"TRUE";
"B \NAC \NWC"8;
"S \NAC"
BN"7"50;
%"TAP"
"6","(700,4650)","2","mstr_standard","I14";
;
CDS_LIB"mstr_standard"
BODY_TYPE"PLUMBING"
HDL_TAP"TRUE";
"B \NAC \NWC"1;
"S \NAC"
BN"12"160;
%"TAP"
"6","(-3250,2750)","0","mstr_standard","I140";
;
CDS_LIB"mstr_standard"
BODY_TYPE"PLUMBING"
HDL_TAP"TRUE";
"B \NAC \NWC"8;
"S \NAC"
BN"4"51;
%"TAP"
"6","(-3250,2700)","0","mstr_standard","I141";
;
CDS_LIB"mstr_standard"
BODY_TYPE"PLUMBING"
HDL_TAP"TRUE";
"B \NAC \NWC"8;
"S \NAC"
BN"5"52;
%"TAP"
"6","(-3250,2650)","0","mstr_standard","I142";
;
CDS_LIB"mstr_standard"
BODY_TYPE"PLUMBING"
HDL_TAP"TRUE";
"B \NAC \NWC"8;
"S \NAC"
BN"2"53;
%"TAP"
"6","(-3250,2600)","0","mstr_standard","I143";
;
CDS_LIB"mstr_standard"
BODY_TYPE"PLUMBING"
HDL_TAP"TRUE";
"B \NAC \NWC"8;
"S \NAC"
BN"3"54;
%"TAP"
"6","(-3250,2550)","0","mstr_standard","I144";
;
CDS_LIB"mstr_standard"
BODY_TYPE"PLUMBING"
HDL_TAP"TRUE";
"B \NAC \NWC"8;
"S \NAC"
BN"0"55;
%"TAP"
"6","(-3250,2500)","0","mstr_standard","I145";
;
CDS_LIB"mstr_standard"
BODY_TYPE"PLUMBING"
HDL_TAP"TRUE";
"B \NAC \NWC"8;
"S \NAC"
BN"1"56;
%"TAP"
"6","(700,4750)","2","mstr_standard","I15";
;
CDS_LIB"mstr_standard"
BODY_TYPE"PLUMBING"
HDL_TAP"TRUE";
"B \NAC \NWC"1;
"S \NAC"
BN"13"162;
%"TAP"
"6","(-3250,3700)","0","mstr_standard","I152";
;
CDS_LIB"mstr_standard"
BODY_TYPE"PLUMBING"
HDL_TAP"TRUE";
"B \NAC \NWC"10;
"S \NAC"
BN"1"43;
%"TAP"
"6","(-3250,3600)","0","mstr_standard","I153";
;
CDS_LIB"mstr_standard"
BODY_TYPE"PLUMBING"
HDL_TAP"TRUE";
"B \NAC \NWC"10;
"S \NAC"
BN"0"46;
%"TAP"
"6","(-3450,3650)","0","mstr_standard","I154";
;
CDS_LIB"mstr_standard"
BODY_TYPE"PLUMBING"
HDL_TAP"TRUE";
"B \NAC \NWC"9;
"S \NAC"
BN"1"44;
%"TAP"
"6","(-3450,3550)","0","mstr_standard","I155";
;
CDS_LIB"mstr_standard"
BODY_TYPE"PLUMBING"
HDL_TAP"TRUE";
"B \NAC \NWC"9;
"S \NAC"
BN"0"57;
%"TAP"
"6","(-3250,3400)","0","mstr_standard","I159";
;
CDS_LIB"mstr_standard"
BODY_TYPE"PLUMBING"
HDL_TAP"TRUE";
"B \NAC \NWC"5;
"S \NAC"
BN"3"45;
%"PVDDQ_KLM"
"1","(-1350,2625)","0","mstr_symbols","I16";
;
VOLTAGE"1.2V"
BOM_COST"MEM"
CDS_LIB"mstr_symbols"
BODY_TYPE"PLUMBING"
ROOM"DDR4_CH_D"
HDL_POWER"PVDDQ_KLM";
"G\NAC"13;
%"TAP"
"6","(-3250,3350)","0","mstr_standard","I160";
;
CDS_LIB"mstr_standard"
BODY_TYPE"PLUMBING"
HDL_TAP"TRUE";
"B \NAC \NWC"5;
"S \NAC"
BN"2"47;
%"TAP"
"6","(-3250,3300)","0","mstr_standard","I161";
;
CDS_LIB"mstr_standard"
BODY_TYPE"PLUMBING"
HDL_TAP"TRUE";
"B \NAC \NWC"5;
"S \NAC"
BN"1"48;
%"TAP"
"6","(-3250,3250)","0","mstr_standard","I162";
;
CDS_LIB"mstr_standard"
BODY_TYPE"PLUMBING"
HDL_TAP"TRUE";
"B \NAC \NWC"5;
"S \NAC"
BN"0"63;
%"TAP"
"6","(-3250,3150)","0","mstr_standard","I163";
;
CDS_LIB"mstr_standard"
BODY_TYPE"PLUMBING"
HDL_TAP"TRUE";
"B \NAC \NWC"6;
"S \NAC"
BN"1"58;
%"TAP"
"6","(-3250,3100)","0","mstr_standard","I166";
;
CDS_LIB"mstr_standard"
BODY_TYPE"PLUMBING"
HDL_TAP"TRUE";
"B \NAC \NWC"6;
"S \NAC"
BN"0"62;
%"TAP"
"6","(-3250,3000)","0","mstr_standard","I167";
;
CDS_LIB"mstr_standard"
BODY_TYPE"PLUMBING"
HDL_TAP"TRUE";
"B \NAC \NWC"7;
"S \NAC"
BN"1"61;
%"TAP"
"6","(-3250,2950)","0","mstr_standard","I168";
;
CDS_LIB"mstr_standard"
BODY_TYPE"PLUMBING"
HDL_TAP"TRUE";
"B \NAC \NWC"7;
"S \NAC"
BN"0"60;
%"PVTT_KLM"
"1","(-1100,2750)","0","mstr_symbols","I17";
;
VOLTAGE"0.6V"
BOM_COST"MEM"
CDS_LIB"mstr_symbols"
BODY_TYPE"PLUMBING"
ROOM"DDR4_CH_D"
HDL_POWER"PVTT_KLM";
"G\NAC"14;
%"SCONN288_H44441004"
"4","(-250,2050)","0","mstr_sconn","I172";
;
CDS_SEC"4"
LOCATION"J1A2"
PART_NUMBER"H44441-004"
MATERIAL"SCONN"
PACK_TYPE"PIP"
BOM_COST"MEM"
CDS_LIB"mstr_sconn"
SEC_TYPE"PIP"
SEC"4"
CDS_LOCATION"J1A2"
ROOM"DDR4_CH_L";
"VPP<4>"
$PN"142"18;
"VTT<1>"
$PN"77"14;
"VPP<0>"
$PN"287"18;
"VPP<1>"
$PN"286"18;
"VPP<2>"
$PN"288"18;
"VPP<3>"
$PN"143"18;
"VDD<1>"
$PN"233"13;
"VDD<2>"
$PN"231"13;
"VDD<3>"
$PN"229"13;
"VDD<4>"
$PN"226"13;
"VDD<5>"
$PN"223"13;
"VDD<7>"
$PN"217"13;
"VDD<8>"
$PN"215"13;
"VDD<9>"
$PN"212"13;
"VDD<11>"
$PN"206"13;
"VDD<12>"
$PN"204"13;
"VDD<14>"
$PN"90"13;
"VDD<15>"
$PN"88"13;
"VDD<17>"
$PN"83"13;
"VDD<18>"
$PN"80"13;
"VDD<20>"
$PN"73"13;
"VDD<21>"
$PN"70"13;
"VDD<22>"
$PN"67"13;
"VDD<24>"
$PN"61"13;
"12V<0>"
$PN"145"20;
"12V<1>"
$PN"1"20;
"VTT<0>"
$PN"221"14;
"VDD<25>"
$PN"59"13;
"VDD<23>"
$PN"64"13;
"VDD<19>"
$PN"76"13;
"VDD<16>"
$PN"85"13;
"VDD<13>"
$PN"92"13;
"VDD<10>"
$PN"209"13;
"VDD<6>"
$PN"220"13;
"VDD<0>"
$PN"236"13;
%"GND"
"1","(2500,1100)","2","mstr_symbols","I173";
;
VOLTAGE"0"
BOM_COST"MEM"
CDS_LIB"mstr_symbols"
SIZE"1B"
BODY_TYPE"PLUMBING"
ROOM"DDR4_CH_D"
HDL_POWER"GND";
"A\NAC"15;
%"GND"
"1","(-5150,1850)","2","mstr_symbols","I175";
;
VOLTAGE"0"
BOM_COST"MEM"
SIZE"1B"
CDS_LIB"mstr_symbols"
BODY_TYPE"PLUMBING"
ROOM"DDR4_CH_D"
HDL_POWER"GND";
"A\NAC"16;
%"GND"
"1","(-4650,1300)","0","mstr_symbols","I180";
;
VOLTAGE"0"
BOM_COST"MEM"
CDS_LIB"mstr_symbols"
SIZE"1B"
BODY_TYPE"PLUMBING"
ROOM"DDR4_CH_D"
HDL_POWER"GND";
"A\NAC"17;
%"CAP_A"
"1","(-4650,1550)","2","dev_discrete","I181";
;
LOCATION"C9L7"
PART_NUMBER"A36096-045"
VALUE"0.01UF"
TOLERANCE"10%"
PACK_TYPE"0402V"
VOLTAGE"25V"
MATERIAL"X7R"
CDS_LOCATION"C9L7"
BOM_COST"MEM"
CDS_LIB"dev_discrete"
CDS_SEC"1"
$SEC"1"
ROOM"DDR4_CH_L";
"B"
$PN"2"17;
"A"
$PN"1"29;
%"PVPP_KLM"
"1","(-950,3075)","0","mstr_symbols","I182";
;
VOLTAGE"2.5V"
BOM_COST"MEM"
CDS_LIB"mstr_symbols"
BODY_TYPE"PLUMBING"
ROOM"DDR4_CH_D"
HDL_POWER"PVPP_KLM";
"G\NAC"18;
%"PVPP_KLM"
"1","(-5150,2250)","0","mstr_symbols","I183";
;
VOLTAGE"2.5V"
BOM_COST"MEM"
CDS_LIB"mstr_symbols"
BODY_TYPE"PLUMBING"
ROOM"DDR4_CH_M"
HDL_POWER"PVPP_KLM";
"G\NAC"19;
%"P12V_NVDIMM_KLM"
"1","(375,3025)","0","mstr_symbols","I185";
;
VOLTAGE"12.0"
CDS_LIB"mstr_symbols"
BODY_TYPE"PLUMBING"
HDL_POWER"P12V_NVDIMM_KLM";
"G\NAC"20;
%"TAP"
"6","(900,4500)","2","mstr_standard","I19";
;
CDS_LIB"mstr_standard"
BODY_TYPE"PLUMBING"
HDL_TAP"TRUE";
"B \NAC \NWC"2;
"S \NAC"
BN"11"157;
%"TAP"
"6","(900,4400)","2","mstr_standard","I20";
;
CDS_LIB"mstr_standard"
BODY_TYPE"PLUMBING"
HDL_TAP"TRUE";
"B \NAC \NWC"2;
"S \NAC"
BN"10"24;
%"TAP"
"6","(900,4300)","2","mstr_standard","I21";
;
CDS_LIB"mstr_standard"
BODY_TYPE"PLUMBING"
HDL_TAP"TRUE";
"B \NAC \NWC"2;
"S \NAC"
BN"9"174;
%"TAP"
"6","(900,4200)","2","mstr_standard","I22";
;
CDS_LIB"mstr_standard"
BODY_TYPE"PLUMBING"
HDL_TAP"TRUE";
"B \NAC \NWC"2;
"S \NAC"
BN"8"172;
%"TAP"
"6","(900,4100)","2","mstr_standard","I23";
;
CDS_LIB"mstr_standard"
BODY_TYPE"PLUMBING"
HDL_TAP"TRUE";
"B \NAC \NWC"2;
"S \NAC"
BN"7"170;
%"TAP"
"6","(700,4450)","2","mstr_standard","I24";
;
CDS_LIB"mstr_standard"
BODY_TYPE"PLUMBING"
HDL_TAP"TRUE";
"B \NAC \NWC"1;
"S \NAC"
BN"10"156;
%"TAP"
"6","(700,4350)","2","mstr_standard","I25";
;
CDS_LIB"mstr_standard"
BODY_TYPE"PLUMBING"
HDL_TAP"TRUE";
"B \NAC \NWC"1;
"S \NAC"
BN"9"175;
%"TAP"
"6","(700,4050)","2","mstr_standard","I26";
;
CDS_LIB"mstr_standard"
BODY_TYPE"PLUMBING"
HDL_TAP"TRUE";
"B \NAC \NWC"1;
"S \NAC"
BN"6"155;
%"TAP"
"6","(700,4150)","2","mstr_standard","I27";
;
CDS_LIB"mstr_standard"
BODY_TYPE"PLUMBING"
HDL_TAP"TRUE";
"B \NAC \NWC"1;
"S \NAC"
BN"7"171;
%"TAP"
"6","(700,4250)","2","mstr_standard","I28";
;
CDS_LIB"mstr_standard"
BODY_TYPE"PLUMBING"
HDL_TAP"TRUE";
"B \NAC \NWC"1;
"S \NAC"
BN"8"173;
%"TAP"
"6","(900,4000)","2","mstr_standard","I29";
;
CDS_LIB"mstr_standard"
BODY_TYPE"PLUMBING"
HDL_TAP"TRUE";
"B \NAC \NWC"2;
"S \NAC"
BN"6"154;
%"TAP"
"6","(900,5100)","2","mstr_standard","I3";
;
CDS_LIB"mstr_standard"
BODY_TYPE"PLUMBING"
HDL_TAP"TRUE";
"B \NAC \NWC"2;
"S \NAC"
BN"17"169;
%"TAP"
"6","(900,3900)","2","mstr_standard","I30";
;
CDS_LIB"mstr_standard"
BODY_TYPE"PLUMBING"
HDL_TAP"TRUE";
"B \NAC \NWC"2;
"S \NAC"
BN"5"152;
%"TAP"
"6","(900,3800)","2","mstr_standard","I31";
;
CDS_LIB"mstr_standard"
BODY_TYPE"PLUMBING"
HDL_TAP"TRUE";
"B \NAC \NWC"2;
"S \NAC"
BN"4"150;
%"TAP"
"6","(900,3700)","2","mstr_standard","I32";
;
CDS_LIB"mstr_standard"
BODY_TYPE"PLUMBING"
HDL_TAP"TRUE";
"B \NAC \NWC"2;
"S \NAC"
BN"3"148;
%"TAP"
"6","(900,3600)","2","mstr_standard","I33";
;
CDS_LIB"mstr_standard"
BODY_TYPE"PLUMBING"
HDL_TAP"TRUE";
"B \NAC \NWC"2;
"S \NAC"
BN"2"146;
%"TAP"
"6","(700,3950)","2","mstr_standard","I34";
;
CDS_LIB"mstr_standard"
BODY_TYPE"PLUMBING"
HDL_TAP"TRUE";
"B \NAC \NWC"1;
"S \NAC"
BN"5"153;
%"TAP"
"6","(700,3850)","2","mstr_standard","I35";
;
CDS_LIB"mstr_standard"
BODY_TYPE"PLUMBING"
HDL_TAP"TRUE";
"B \NAC \NWC"1;
"S \NAC"
BN"4"151;
%"TAP"
"6","(700,3650)","2","mstr_standard","I36";
;
CDS_LIB"mstr_standard"
BODY_TYPE"PLUMBING"
HDL_TAP"TRUE";
"B \NAC \NWC"1;
"S \NAC"
BN"2"147;
%"TAP"
"6","(700,3550)","2","mstr_standard","I37";
;
CDS_LIB"mstr_standard"
BODY_TYPE"PLUMBING"
HDL_TAP"TRUE";
"B \NAC \NWC"1;
"S \NAC"
BN"1"145;
%"TAP"
"6","(700,3750)","2","mstr_standard","I38";
;
CDS_LIB"mstr_standard"
BODY_TYPE"PLUMBING"
HDL_TAP"TRUE";
"B \NAC \NWC"1;
"S \NAC"
BN"3"149;
%"TAP"
"6","(900,3400)","2","mstr_standard","I39";
;
CDS_LIB"mstr_standard"
BODY_TYPE"PLUMBING"
HDL_TAP"TRUE";
"B \NAC \NWC"2;
"S \NAC"
BN"0"22;
%"TAP"
"6","(700,5150)","2","mstr_standard","I4";
;
CDS_LIB"mstr_standard"
BODY_TYPE"PLUMBING"
HDL_TAP"TRUE";
"B \NAC \NWC"1;
"S \NAC"
BN"17"176;
%"TAP"
"6","(900,3500)","2","mstr_standard","I40";
;
CDS_LIB"mstr_standard"
BODY_TYPE"PLUMBING"
HDL_TAP"TRUE";
"B \NAC \NWC"2;
"S \NAC"
BN"1"144;
%"TAP"
"6","(700,3450)","2","mstr_standard","I41";
;
CDS_LIB"mstr_standard"
BODY_TYPE"PLUMBING"
HDL_TAP"TRUE";
"B \NAC \NWC"1;
"S \NAC"
BN"0"143;
%"SCONN288_H44441004"
"3","(1800,2400)","0","mstr_sconn","I43";
;
CDS_SEC"3"
PART_NUMBER"H44441-004"
LOCATION"J1A2"
MATERIAL"SCONN"
PACK_TYPE"PIP"
BOM_COST"MEM"
CDS_LIB"mstr_sconn"
SEC_TYPE"PIP"
SEC"3"
CDS_LOCATION"J1A2"
ROOM"DDR4_CH_L";
"VSS<93>"
$PN"2"21;
"VSS<92>"
$PN"4"21;
"VSS<91>"
$PN"6"21;
"VSS<90>"
$PN"9"21;
"VSS<89>"
$PN"11"21;
"VSS<88>"
$PN"13"21;
"VSS<0>"
$PN"283"15;
"VSS<1>"
$PN"281"15;
"VSS<2>"
$PN"279"15;
"VSS<3>"
$PN"276"15;
"VSS<4>"
$PN"274"15;
"VSS<5>"
$PN"272"15;
"VSS<6>"
$PN"270"15;
"VSS<7>"
$PN"268"15;
"VSS<8>"
$PN"265"15;
"VSS<9>"
$PN"263"15;
"VSS<10>"
$PN"261"15;
"VSS<11>"
$PN"259"15;
"VSS<12>"
$PN"257"15;
"VSS<13>"
$PN"254"15;
"VSS<14>"
$PN"252"15;
"VSS<15>"
$PN"250"15;
"VSS<16>"
$PN"248"15;
"VSS<17>"
$PN"246"15;
"VSS<18>"
$PN"243"15;
"VSS<19>"
$PN"241"15;
"VSS<20>"
$PN"239"15;
"VSS<21>"
$PN"202"15;
"VSS<22>"
$PN"200"15;
"VSS<23>"
$PN"198"15;
"VSS<24>"
$PN"195"15;
"VSS<25>"
$PN"193"15;
"VSS<26>"
$PN"191"15;
"VSS<27>"
$PN"189"15;
"VSS<28>"
$PN"187"15;
"VSS<29>"
$PN"184"15;
"VSS<30>"
$PN"182"15;
"VSS<31>"
$PN"180"15;
"VSS<32>"
$PN"178"15;
"VSS<33>"
$PN"176"15;
"VSS<34>"
$PN"173"15;
"VSS<35>"
$PN"171"15;
"VSS<36>"
$PN"169"15;
"VSS<37>"
$PN"167"15;
"VSS<38>"
$PN"165"15;
"VSS<39>"
$PN"162"15;
"VSS<40>"
$PN"160"15;
"VSS<41>"
$PN"158"15;
"VSS<42>"
$PN"156"15;
"VSS<43>"
$PN"154"15;
"VSS<44>"
$PN"151"15;
"VSS<47>"
$PN"138"21;
"VSS<48>"
$PN"136"21;
"VSS<49>"
$PN"134"21;
"VSS<50>"
$PN"131"21;
"VSS<51>"
$PN"129"21;
"VSS<52>"
$PN"127"21;
"VSS<53>"
$PN"125"21;
"VSS<54>"
$PN"123"21;
"VSS<55>"
$PN"120"21;
"VSS<56>"
$PN"118"21;
"VSS<57>"
$PN"116"21;
"VSS<58>"
$PN"114"21;
"VSS<59>"
$PN"112"21;
"VSS<60>"
$PN"109"21;
"VSS<61>"
$PN"107"21;
"VSS<62>"
$PN"105"21;
"VSS<63>"
$PN"103"21;
"VSS<64>"
$PN"101"21;
"VSS<65>"
$PN"98"21;
"VSS<66>"
$PN"96"21;
"VSS<67>"
$PN"94"21;
"VSS<68>"
$PN"57"21;
"VSS<69>"
$PN"55"21;
"VSS<70>"
$PN"53"21;
"VSS<71>"
$PN"50"21;
"VSS<72>"
$PN"48"21;
"VSS<73>"
$PN"46"21;
"VSS<74>"
$PN"44"21;
"VSS<75>"
$PN"42"21;
"VSS<76>"
$PN"39"21;
"VSS<77>"
$PN"37"21;
"VSS<78>"
$PN"35"21;
"VSS<79>"
$PN"33"21;
"VSS<80>"
$PN"31"21;
"VSS<81>"
$PN"28"21;
"VSS<82>"
$PN"26"21;
"VSS<83>"
$PN"24"21;
"VSS<84>"
$PN"22"21;
"VSS<85>"
$PN"20"21;
"VSS<86>"
$PN"17"21;
"VSS<87>"
$PN"15"21;
"VSS<45>"
$PN"149"15;
"VSS<46>"
$PN"147"15;
%"GND"
"1","(1100,1100)","2","mstr_symbols","I44";
;
VOLTAGE"0"
BOM_COST"MEM"
CDS_LIB"mstr_symbols"
SIZE"1B"
BODY_TYPE"PLUMBING"
ROOM"DDR4_CH_D"
HDL_POWER"GND";
"A\NAC"21;
%"TAP"
"6","(-1750,4800)","2","mstr_standard","I46";
;
CDS_LIB"mstr_standard"
BODY_TYPE"PLUMBING"
HDL_TAP"TRUE";
"B \NAC \NWC"3;
"S \NAC"
BN"60"139;
%"TAP"
"6","(-1750,4750)","2","mstr_standard","I47";
;
CDS_LIB"mstr_standard"
BODY_TYPE"PLUMBING"
HDL_TAP"TRUE";
"B \NAC \NWC"3;
"S \NAC"
BN"61"140;
%"TAP"
"6","(-1750,4850)","2","mstr_standard","I48";
;
CDS_LIB"mstr_standard"
BODY_TYPE"PLUMBING"
HDL_TAP"TRUE";
"B \NAC \NWC"3;
"S \NAC"
BN"63"141;
%"TAP"
"6","(-1750,4900)","2","mstr_standard","I49";
;
CDS_LIB"mstr_standard"
BODY_TYPE"PLUMBING"
HDL_TAP"TRUE";
"B \NAC \NWC"3;
"S \NAC"
BN"62"142;
%"TAP"
"6","(900,5000)","2","mstr_standard","I5";
;
CDS_LIB"mstr_standard"
BODY_TYPE"PLUMBING"
HDL_TAP"TRUE";
"B \NAC \NWC"2;
"S \NAC"
BN"16"167;
%"TAP"
"6","(-1750,4500)","2","mstr_standard","I50";
;
CDS_LIB"mstr_standard"
BODY_TYPE"PLUMBING"
HDL_TAP"TRUE";
"B \NAC \NWC"3;
"S \NAC"
BN"54"134;
%"TAP"
"6","(-1750,4550)","2","mstr_standard","I51";
;
CDS_LIB"mstr_standard"
BODY_TYPE"PLUMBING"
HDL_TAP"TRUE";
"B \NAC \NWC"3;
"S \NAC"
BN"57"135;
%"TAP"
"6","(-1750,4650)","2","mstr_standard","I52";
;
CDS_LIB"mstr_standard"
BODY_TYPE"PLUMBING"
HDL_TAP"TRUE";
"B \NAC \NWC"3;
"S \NAC"
BN"59"26;
%"TAP"
"6","(-1750,4600)","2","mstr_standard","I53";
;
CDS_LIB"mstr_standard"
BODY_TYPE"PLUMBING"
HDL_TAP"TRUE";
"B \NAC \NWC"3;
"S \NAC"
BN"56"136;
%"TAP"
"6","(-1750,4700)","2","mstr_standard","I54";
;
CDS_LIB"mstr_standard"
BODY_TYPE"PLUMBING"
HDL_TAP"TRUE";
"B \NAC \NWC"3;
"S \NAC"
BN"58"25;
%"TAP"
"6","(-1750,4250)","2","mstr_standard","I55";
;
CDS_LIB"mstr_standard"
BODY_TYPE"PLUMBING"
HDL_TAP"TRUE";
"B \NAC \NWC"3;
"S \NAC"
BN"51"131;
%"TAP"
"6","(-1750,4300)","2","mstr_standard","I56";
;
CDS_LIB"mstr_standard"
BODY_TYPE"PLUMBING"
HDL_TAP"TRUE";
"B \NAC \NWC"3;
"S \NAC"
BN"50"132;
%"TAP"
"6","(-1750,4350)","2","mstr_standard","I57";
;
CDS_LIB"mstr_standard"
BODY_TYPE"PLUMBING"
HDL_TAP"TRUE";
"B \NAC \NWC"3;
"S \NAC"
BN"53"133;
%"TAP"
"6","(-1750,4450)","2","mstr_standard","I58";
;
CDS_LIB"mstr_standard"
BODY_TYPE"PLUMBING"
HDL_TAP"TRUE";
"B \NAC \NWC"3;
"S \NAC"
BN"55"137;
%"TAP"
"6","(-1750,4400)","2","mstr_standard","I59";
;
CDS_LIB"mstr_standard"
BODY_TYPE"PLUMBING"
HDL_TAP"TRUE";
"B \NAC \NWC"3;
"S \NAC"
BN"52"138;
%"TAP"
"6","(900,4900)","2","mstr_standard","I6";
;
CDS_LIB"mstr_standard"
BODY_TYPE"PLUMBING"
HDL_TAP"TRUE";
"B \NAC \NWC"2;
"S \NAC"
BN"15"165;
%"TAP"
"6","(-1750,3950)","2","mstr_standard","I60";
;
CDS_LIB"mstr_standard"
BODY_TYPE"PLUMBING"
HDL_TAP"TRUE";
"B \NAC \NWC"3;
"S \NAC"
BN"45"107;
%"TAP"
"6","(-1750,4000)","2","mstr_standard","I61";
;
CDS_LIB"mstr_standard"
BODY_TYPE"PLUMBING"
HDL_TAP"TRUE";
"B \NAC \NWC"3;
"S \NAC"
BN"44"108;
%"TAP"
"6","(-1750,4050)","2","mstr_standard","I62";
;
CDS_LIB"mstr_standard"
BODY_TYPE"PLUMBING"
HDL_TAP"TRUE";
"B \NAC \NWC"3;
"S \NAC"
BN"47"109;
%"TAP"
"6","(-1750,4150)","2","mstr_standard","I63";
;
CDS_LIB"mstr_standard"
BODY_TYPE"PLUMBING"
HDL_TAP"TRUE";
"B \NAC \NWC"3;
"S \NAC"
BN"49"129;
%"TAP"
"6","(-1750,4100)","2","mstr_standard","I64";
;
CDS_LIB"mstr_standard"
BODY_TYPE"PLUMBING"
HDL_TAP"TRUE";
"B \NAC \NWC"3;
"S \NAC"
BN"46"128;
%"TAP"
"6","(-1750,4200)","2","mstr_standard","I65";
;
CDS_LIB"mstr_standard"
BODY_TYPE"PLUMBING"
HDL_TAP"TRUE";
"B \NAC \NWC"3;
"S \NAC"
BN"48"130;
%"SCONN288_H44441004"
"2","(0,4300)","0","mstr_sconn","I66";
;
CDS_SEC"2"
LOCATION"J1A2"
PART_NUMBER"H44441-004"
MATERIAL"SCONN"
PACK_TYPE"PIP"
BOM_COST"MEM"
CDS_LIB"mstr_sconn"
SEC_TYPE"PIP"
SEC"2"
CDS_LOCATION"J1A2"
ROOM"DDR4_CH_L";
"DQS17P"
$PN"51"176;
"DQS9P"
$PN"7"175;
"DQS9N"
$PN"8"174;
"DQS8P"
$PN"197"173;
"DQS8N"
$PN"196"172;
"DQS7P"
$PN"278"171;
"DQS7N"
$PN"277"170;
"DQS6P"
$PN"267"155;
"DQS6N"
$PN"266"154;
"DQS5P"
$PN"256"153;
"DQS5N"
$PN"255"152;
"DQS4P"
$PN"245"151;
"DQS4N"
$PN"244"150;
"DQS3P"
$PN"186"149;
"DQS3N"
$PN"185"148;
"DQS2P"
$PN"175"147;
"DQS2N"
$PN"174"146;
"DQS1P"
$PN"164"145;
"DQS1N"
$PN"163"144;
"DQS17N"
$PN"52"169;
"DQS16P"
$PN"132"168;
"DQS16N"
$PN"133"167;
"DQS15P"
$PN"121"166;
"DQS15N"
$PN"122"165;
"DQS14P"
$PN"110"164;
"DQS14N"
$PN"111"163;
"DQS13P"
$PN"99"162;
"DQS13N"
$PN"100"161;
"DQS12P"
$PN"40"160;
"DQS12N"
$PN"41"159;
"DQS11P"
$PN"29"158;
"DQS11N"
$PN"30"157;
"DQS10P"
$PN"18"156;
"DQS10N"
$PN"19"24;
"DQS0P"
$PN"153"143;
"DQS0N"
$PN"152"22;
%"TAP"
"6","(-1750,3800)","2","mstr_standard","I67";
;
CDS_LIB"mstr_standard"
BODY_TYPE"PLUMBING"
HDL_TAP"TRUE";
"B \NAC \NWC"3;
"S \NAC"
BN"40"103;
%"TAP"
"6","(-1750,3700)","2","mstr_standard","I68";
;
CDS_LIB"mstr_standard"
BODY_TYPE"PLUMBING"
HDL_TAP"TRUE";
"B \NAC \NWC"3;
"S \NAC"
BN"38"102;
%"TAP"
"6","(-1750,3750)","2","mstr_standard","I69";
;
CDS_LIB"mstr_standard"
BODY_TYPE"PLUMBING"
HDL_TAP"TRUE";
"B \NAC \NWC"3;
"S \NAC"
BN"41"104;
%"TAP"
"6","(900,4800)","2","mstr_standard","I7";
;
CDS_LIB"mstr_standard"
BODY_TYPE"PLUMBING"
HDL_TAP"TRUE";
"B \NAC \NWC"2;
"S \NAC"
BN"14"163;
%"TAP"
"6","(-1750,3850)","2","mstr_standard","I70";
;
CDS_LIB"mstr_standard"
BODY_TYPE"PLUMBING"
HDL_TAP"TRUE";
"B \NAC \NWC"3;
"S \NAC"
BN"43"110;
%"TAP"
"6","(-1750,3900)","2","mstr_standard","I71";
;
CDS_LIB"mstr_standard"
BODY_TYPE"PLUMBING"
HDL_TAP"TRUE";
"B \NAC \NWC"3;
"S \NAC"
BN"42"106;
%"TAP"
"6","(-1750,3500)","2","mstr_standard","I72";
;
CDS_LIB"mstr_standard"
BODY_TYPE"PLUMBING"
HDL_TAP"TRUE";
"B \NAC \NWC"3;
"S \NAC"
BN"34"100;
%"TAP"
"6","(-1750,3450)","2","mstr_standard","I73";
;
CDS_LIB"mstr_standard"
BODY_TYPE"PLUMBING"
HDL_TAP"TRUE";
"B \NAC \NWC"3;
"S \NAC"
BN"35"98;
%"TAP"
"6","(-1750,3550)","2","mstr_standard","I74";
;
CDS_LIB"mstr_standard"
BODY_TYPE"PLUMBING"
HDL_TAP"TRUE";
"B \NAC \NWC"3;
"S \NAC"
BN"37"101;
%"TAP"
"6","(-1750,3600)","2","mstr_standard","I75";
;
CDS_LIB"mstr_standard"
BODY_TYPE"PLUMBING"
HDL_TAP"TRUE";
"B \NAC \NWC"3;
"S \NAC"
BN"36"27;
%"TAP"
"6","(-1750,3650)","2","mstr_standard","I76";
;
CDS_LIB"mstr_standard"
BODY_TYPE"PLUMBING"
HDL_TAP"TRUE";
"B \NAC \NWC"3;
"S \NAC"
BN"39"105;
%"TAP"
"6","(-1750,3250)","2","mstr_standard","I77";
;
CDS_LIB"mstr_standard"
BODY_TYPE"PLUMBING"
HDL_TAP"TRUE";
"B \NAC \NWC"3;
"S \NAC"
BN"31"95;
%"TAP"
"6","(-1750,3300)","2","mstr_standard","I78";
;
CDS_LIB"mstr_standard"
BODY_TYPE"PLUMBING"
HDL_TAP"TRUE";
"B \NAC \NWC"3;
"S \NAC"
BN"30"94;
%"TAP"
"6","(-1750,3200)","2","mstr_standard","I79";
;
CDS_LIB"mstr_standard"
BODY_TYPE"PLUMBING"
HDL_TAP"TRUE";
"B \NAC \NWC"3;
"S \NAC"
BN"28"92;
%"TAP"
"6","(900,4700)","2","mstr_standard","I8";
;
CDS_LIB"mstr_standard"
BODY_TYPE"PLUMBING"
HDL_TAP"TRUE";
"B \NAC \NWC"2;
"S \NAC"
BN"13"161;
%"TAP"
"6","(-1750,3350)","2","mstr_standard","I80";
;
CDS_LIB"mstr_standard"
BODY_TYPE"PLUMBING"
HDL_TAP"TRUE";
"B \NAC \NWC"3;
"S \NAC"
BN"33"99;
%"TAP"
"6","(-1750,3400)","2","mstr_standard","I81";
;
CDS_LIB"mstr_standard"
BODY_TYPE"PLUMBING"
HDL_TAP"TRUE";
"B \NAC \NWC"3;
"S \NAC"
BN"32"97;
%"TAP"
"6","(-1750,3000)","2","mstr_standard","I82";
;
CDS_LIB"mstr_standard"
BODY_TYPE"PLUMBING"
HDL_TAP"TRUE";
"B \NAC \NWC"3;
"S \NAC"
BN"24"90;
%"TAP"
"6","(-1750,2950)","2","mstr_standard","I83";
;
CDS_LIB"mstr_standard"
BODY_TYPE"PLUMBING"
HDL_TAP"TRUE";
"B \NAC \NWC"3;
"S \NAC"
BN"25"89;
%"TAP"
"6","(-1750,3050)","2","mstr_standard","I84";
;
CDS_LIB"mstr_standard"
BODY_TYPE"PLUMBING"
HDL_TAP"TRUE";
"B \NAC \NWC"3;
"S \NAC"
BN"27"91;
%"TAP"
"6","(-1750,3150)","2","mstr_standard","I85";
;
CDS_LIB"mstr_standard"
BODY_TYPE"PLUMBING"
HDL_TAP"TRUE";
"B \NAC \NWC"3;
"S \NAC"
BN"29"93;
%"TAP"
"6","(-1750,3100)","2","mstr_standard","I86";
;
CDS_LIB"mstr_standard"
BODY_TYPE"PLUMBING"
HDL_TAP"TRUE";
"B \NAC \NWC"3;
"S \NAC"
BN"26"96;
%"TAP"
"6","(-1750,2700)","2","mstr_standard","I87";
;
CDS_LIB"mstr_standard"
BODY_TYPE"PLUMBING"
HDL_TAP"TRUE";
"B \NAC \NWC"3;
"S \NAC"
BN"18"82;
%"TAP"
"6","(-1750,2750)","2","mstr_standard","I88";
;
CDS_LIB"mstr_standard"
BODY_TYPE"PLUMBING"
HDL_TAP"TRUE";
"B \NAC \NWC"3;
"S \NAC"
BN"21"84;
%"TAP"
"6","(-1750,2800)","2","mstr_standard","I89";
;
CDS_LIB"mstr_standard"
BODY_TYPE"PLUMBING"
HDL_TAP"TRUE";
"B \NAC \NWC"3;
"S \NAC"
BN"20"83;
%"TAP"
"6","(900,4600)","2","mstr_standard","I9";
;
CDS_LIB"mstr_standard"
BODY_TYPE"PLUMBING"
HDL_TAP"TRUE";
"B \NAC \NWC"2;
"S \NAC"
BN"12"159;
%"TAP"
"6","(-1750,2900)","2","mstr_standard","I90";
;
CDS_LIB"mstr_standard"
BODY_TYPE"PLUMBING"
HDL_TAP"TRUE";
"B \NAC \NWC"3;
"S \NAC"
BN"22"88;
%"TAP"
"6","(-1750,2850)","2","mstr_standard","I91";
;
CDS_LIB"mstr_standard"
BODY_TYPE"PLUMBING"
HDL_TAP"TRUE";
"B \NAC \NWC"3;
"S \NAC"
BN"23"87;
%"TAP"
"6","(-1750,2450)","2","mstr_standard","I92";
;
CDS_LIB"mstr_standard"
BODY_TYPE"PLUMBING"
HDL_TAP"TRUE";
"B \NAC \NWC"3;
"S \NAC"
BN"15"78;
%"TAP"
"6","(-1750,2500)","2","mstr_standard","I93";
;
CDS_LIB"mstr_standard"
BODY_TYPE"PLUMBING"
HDL_TAP"TRUE";
"B \NAC \NWC"3;
"S \NAC"
BN"14"81;
%"TAP"
"6","(-1750,2600)","2","mstr_standard","I94";
;
CDS_LIB"mstr_standard"
BODY_TYPE"PLUMBING"
HDL_TAP"TRUE";
"B \NAC \NWC"3;
"S \NAC"
BN"16"86;
%"TAP"
"6","(-1750,2550)","2","mstr_standard","I95";
;
CDS_LIB"mstr_standard"
BODY_TYPE"PLUMBING"
HDL_TAP"TRUE";
"B \NAC \NWC"3;
"S \NAC"
BN"17"77;
%"TAP"
"6","(-1750,2650)","2","mstr_standard","I96";
;
CDS_LIB"mstr_standard"
BODY_TYPE"PLUMBING"
HDL_TAP"TRUE";
"B \NAC \NWC"3;
"S \NAC"
BN"19"85;
%"TAP"
"6","(-1750,2400)","2","mstr_standard","I97";
;
CDS_LIB"mstr_standard"
BODY_TYPE"PLUMBING"
HDL_TAP"TRUE";
"B \NAC \NWC"3;
"S \NAC"
BN"12"79;
%"TAP"
"6","(-1750,2300)","2","mstr_standard","I98";
;
CDS_LIB"mstr_standard"
BODY_TYPE"PLUMBING"
HDL_TAP"TRUE";
"B \NAC \NWC"3;
"S \NAC"
BN"10"71;
%"TAP"
"6","(-1750,2350)","2","mstr_standard","I99";
;
CDS_LIB"mstr_standard"
BODY_TYPE"PLUMBING"
HDL_TAP"TRUE";
"B \NAC \NWC"3;
"S \NAC"
BN"13"80;
END.
